# T6G (Grand Teton) — schematic netlist excerpt (pin names and nets, part order shuffled) for the footprints in the layout excerpt that follows; sources: Cadence DE-HDL packaged netlist, KiCad conversion of 04192023_DAF0TMB3IC0_F0TG_MB_C_brd_V02_OCP.brd

J26  SCONN288_DDR506112002KQ  IO  pkg DDR288S_1-1VXC  page 99
  VIN_BULK0  = P12V_MEM_CPU1
  RFU0  = NC
  VIN_MGMT  = P3V3_AUX
  HSCL  = I3C_SPD_DDRB_CPU1_SCL
  HSDA  = I3C_SPD_DDRB_CPU1_SDA
  VSS0  = GND
  DQ0_A  = M_B_CPU1_SA_DQ<0>
  VSS1  = GND
  DQ1_A  = M_B_CPU1_SA_DQ<1>
  VSS2  = GND
  DQS0_A_T  = M_B_CPU1_SA_DQS_DP<0>
  DQS0_A_C  = M_B_CPU1_SA_DQS_DN<0>
  VSS3  = GND
  DQ4_A  = M_B_CPU1_SA_DQ<4>
  VSS4  = GND
  DQ5_A  = M_B_CPU1_SA_DQ<5>
  VSS5  = GND
  DQ8_A  = M_B_CPU1_SA_DQ<8>
  VSS6  = GND
  DQ9_A  = M_B_CPU1_SA_DQ<9>
  VSS7  = GND
  DQS1_A_T  = M_B_CPU1_SA_DQS_DP<1>
  DQS1_A_C  = M_B_CPU1_SA_DQS_DN<1>
  VSS8  = GND
  DQ12_A  = M_B_CPU1_SA_DQ<12>
  VSS9  = GND
  DQ13_A  = M_B_CPU1_SA_DQ<13>
  VSS10  = GND
  DQ16_A  = M_B_CPU1_SA_DQ<16>
  VSS11  = GND
  DQ17_A  = M_B_CPU1_SA_DQ<17>
  VSS12  = GND
  DQS2_A_T  = M_B_CPU1_SA_DQS_DP<2>
  DQS2_A_C  = M_B_CPU1_SA_DQS_DN<2>
  VSS13  = GND
  DQ20_A  = M_B_CPU1_SA_DQ<20>
  VSS14  = GND
  DQ21_A  = M_B_CPU1_SA_DQ<21>
  VSS15  = GND
  DQ24_A  = M_B_CPU1_SA_DQ<24>
  VSS16  = GND
  DQ25_A  = M_B_CPU1_SA_DQ<25>
  VSS17  = GND
  DQS3_A_T  = M_B_CPU1_SA_DQS_DP<3>
  DQS3_A_C  = M_B_CPU1_SA_DQS_DN<3>
  VSS18  = GND
  DQ28_A  = M_B_CPU1_SA_DQ<28>
  VSS19  = GND
  DQ29_A  = M_B_CPU1_SA_DQ<29>
  VSS20  = GND
  CB0_A  = M_B_CPU1_SA_CB<0>
  VSS21  = GND
  CB1_A  = M_B_CPU1_SA_CB<1>
  VSS22  = GND
  DQS4_A_T  = M_B_CPU1_SA_DQS_DP<4>
  DQS4_A_C  = M_B_CPU1_SA_DQS_DN<4>
  VSS23  = GND
  CB4_A  = M_B_CPU1_SA_CB<4>
  VSS24  = GND
  CB5_A  = M_B_CPU1_SA_CB<5>
  VSS25  = GND
  ALERT_N  = M_B_CPU1_ALERT_N
  VSS26  = GND
  CS0_A_N  = M_B_CPU1_SA_CS_N<0>
  VSS27  = GND
  CA0_A  = M_B_CPU1_SA_CA<0>
  VSS28  = GND
  CA2_A  = M_B_CPU1_SA_CA<2>
  VSS29  = GND
  CA4_A  = M_B_CPU1_SA_CA<4>
  VSS30  = GND
  CA6_A  = M_B_CPU1_SA_CA<6>
  VSS31  = GND
  PAR_A  = M_B_CPU1_SA_PAR
  VSS32  = GND
  CA0_B  = M_B_CPU1_SB_CA<0>
  VSS33  = GND
  CA2_B  = M_B_CPU1_SB_CA<2>
  VSS34  = GND
  CA4_B  = M_B_CPU1_SB_CA<4>
  VSS35  = GND
  CA6_B  = M_B_CPU1_SB_CA<6>
  VSS36  = GND
  CS0_B_N  = M_B_CPU1_SB_CS_N<0>
  VSS37  = GND
  \lbd||rsp_a_n\  = M_B_CPU1_SA_RSP<0>
  \lbs||rsp_b_n\  = M_B_CPU1_SB_RSP<0>
  VSS38  = GND
  CB4_B  = M_B_CPU1_SB_CB<4>
  VSS39  = GND
  CB5_B  = M_B_CPU1_SB_CB<5>
  VSS40  = GND
  \dqs9_b_t||tdqs9_b_t||dbi4_b_n\  = M_B_CPU1_SB_DQS_DP<9>
  \dqs9_b_c||tdqs9_b_c\  = M_B_CPU1_SB_DQS_DN<9>
  VSS41  = GND
  CB0_B  = M_B_CPU1_SB_CB<0>
  VSS42  = GND
  CB1_B  = M_B_CPU1_SB_CB<1>
  VSS43  = GND
  DQ0_B  = M_B_CPU1_SB_DQ<0>
  VSS44  = GND
  DQ1_B  = M_B_CPU1_SB_DQ<1>
  VSS45  = GND
  DQS0_B_T  = M_B_CPU1_SB_DQS_DP<0>
  DQS0_B_C  = M_B_CPU1_SB_DQS_DN<0>
  VSS46  = GND
  DQ4_B  = M_B_CPU1_SB_DQ<4>
  VSS47  = GND
  DQ5_B  = M_B_CPU1_SB_DQ<5>
  VSS48  = GND
  DQ8_B  = M_B_CPU1_SB_DQ<8>
  VSS49  = GND
  DQ9_B  = M_B_CPU1_SB_DQ<9>
  VSS50  = GND
  DQS1_B_T  = M_B_CPU1_SB_DQS_DP<1>
  DQS1_B_C  = M_B_CPU1_SB_DQS_DN<1>
  VSS51  = GND
  DQ12_B  = M_B_CPU1_SB_DQ<12>
  VSS52  = GND
  DQ13_B  = M_B_CPU1_SB_DQ<13>
  VSS53  = GND
  DQ16_B  = M_B_CPU1_SB_DQ<16>
  VSS54  = GND
  DQ17_B  = M_B_CPU1_SB_DQ<17>
  VSS55  = GND
  DQS2_B_T  = M_B_CPU1_SB_DQS_DP<2>
  DQS2_B_C  = M_B_CPU1_SB_DQS_DN<2>
  VSS56  = GND
  DQ20_B  = M_B_CPU1_SB_DQ<20>
  VSS57  = GND
  DQ21_B  = M_B_CPU1_SB_DQ<21>
  VSS58  = GND
  DQ24_B  = M_B_CPU1_SB_DQ<24>
  VSS59  = GND
  DQ25_B  = M_B_CPU1_SB_DQ<25>
  VSS60  = GND
  DQS3_B_T  = M_B_CPU1_SB_DQS_DP<3>
  DQS3_B_C  = M_B_CPU1_SB_DQS_DN<3>
  VSS61  = GND
  DQ28_B  = M_B_CPU1_SB_DQ<28>
  VSS62  = GND
  DQ29_B  = M_B_CPU1_SB_DQ<29>
  VSS63  = GND
  RFU1  = NC
  VIN_BULK1  = P12V_MEM_CPU1
  VIN_BULK2  = P12V_MEM_CPU1
  \pwr_good||fail_n\  = PWRGD_CHB_CPU1_DIMM
  HAS  = PD_CHB_CPU1_DIMM_SAA
  RFU2  = NC
  RFU3  = NC
  VSS64  = GND
  DQ2_A  = M_B_CPU1_SA_DQ<2>
  VSS65  = GND
  DQ3_A  = M_B_CPU1_SA_DQ<3>
  VSS66  = GND
  \dqs5_a_c||tdqs5_a_c||dqs5_a_t||tdqs5_a_t\  = M_B_CPU1_SA_DQS_DN<5>
  \dqs5_a_t||tdqs5_a_t\  = M_B_CPU1_SA_DQS_DP<5>
  VSS67  = GND
  DQ6_A  = M_B_CPU1_SA_DQ<6>
  VSS68  = GND
  DQ7_A  = M_B_CPU1_SA_DQ<7>
  VSS69  = GND
  DQ10_A  = M_B_CPU1_SA_DQ<10>
  VSS70  = GND
  DQ11_A  = M_B_CPU1_SA_DQ<11>
  VSS71  = GND
  \dqs6_a_c||tdqs6_a_c||dqs6_a_t||tdqs6_a_t\  = M_B_CPU1_SA_DQS_DN<6>
  \dqs6_a_t||tdqs6_a_t\  = M_B_CPU1_SA_DQS_DP<6>
  VSS72  = GND
  DQ14_A  = M_B_CPU1_SA_DQ<14>
  VSS73  = GND
  DQ15_A  = M_B_CPU1_SA_DQ<15>
  VSS74  = GND
  DQ18_A  = M_B_CPU1_SA_DQ<18>
  VSS75  = GND
  DQ19_A  = M_B_CPU1_SA_DQ<19>
  VSS76  = GND
  \dqs7_a_c||tdqs7_a_c\  = M_B_CPU1_SA_DQS_DN<7>
  \dqs7_a_t||tdqs7_a_t\  = M_B_CPU1_SA_DQS_DP<7>
  VSS77  = GND
  DQ22_A  = M_B_CPU1_SA_DQ<22>
  VSS78  = GND
  DQ23_A  = M_B_CPU1_SA_DQ<23>
  VSS79  = GND
  DQ26_A  = M_B_CPU1_SA_DQ<26>
  VSS80  = GND
  DQ27_A  = M_B_CPU1_SA_DQ<27>
  VSS81  = GND
  \dqs8_a_c||tdqs8_a_c\  = M_B_CPU1_SA_DQS_DN<8>
  \dqs8_a_t||tdqs8_a_t\  = M_B_CPU1_SA_DQS_DP<8>
  VSS82  = GND
  DQ30_A  = M_B_CPU1_SA_DQ<30>
  VSS83  = GND
  DQ31_A  = M_B_CPU1_SA_DQ<31>
  VSS84  = GND
  CB2_A  = M_B_CPU1_SA_CB<2>
  VSS85  = GND
  CB3_A  = M_B_CPU1_SA_CB<3>
  VSS86  = GND
  \dqs9_a_c||tdqs9_a_c\  = M_B_CPU1_SA_DQS_DN<9>
  \dqs9_a_t||tdqs9_a_t\  = M_B_CPU1_SA_DQS_DP<9>
  VSS87  = GND
  CB6_A  = M_B_CPU1_SA_CB<6>
  VSS88  = GND
  CB7_A  = M_B_CPU1_SA_CB<7>
  VSS89  = GND
  RESET_N  = M_B_CPU1_RESET_N
  VSS90  = GND
  CS1_A_N  = M_B_CPU1_SA_CS_N<1>
  VSS91  = GND
  CA1_A  = M_B_CPU1_SA_CA<1>
  VSS92  = GND
  CA3_A  = M_B_CPU1_SA_CA<3>
  VSS93  = GND
  CA5_A  = M_B_CPU1_SA_CA<5>
  VSS94  = GND
  CK_T  = M_B_CPU1_CLK_DP<0>
  CK_C  = M_B_CPU1_CLK_DN<0>
  VSS95  = GND
  RFU4  = NC
  CA1_B  = M_B_CPU1_SB_CA<1>
  VSS96  = GND
  CA3_B  = M_B_CPU1_SB_CA<3>
  VSS97  = GND
  CA5_B  = M_B_CPU1_SB_CA<5>
  VSS98  = GND
  PAR_B  = M_B_CPU1_SB_PAR
  VSS99  = GND
  CS1_B_N  = M_B_CPU1_SB_CS_N<1>
  VSS100  = GND
  RFU5  = NC
  RFU6  = NC
  VSS101  = GND
  CB6_B  = M_B_CPU1_SB_CB<6>
  VSS102  = GND
  CB7_B  = M_B_CPU1_SB_CB<7>
  VSS103  = GND
  DQS4_B_C  = M_B_CPU1_SB_DQS_DN<4>
  DQS4_B_T  = M_B_CPU1_SB_DQS_DP<4>
  VSS104  = GND
  CB2_B  = M_B_CPU1_SB_CB<2>
  VSS105  = GND
  CB3_B  = M_B_CPU1_SB_CB<3>
  VSS106  = GND
  DQ2_B  = M_B_CPU1_SB_DQ<2>
  VSS107  = GND
  DQ3_B  = M_B_CPU1_SB_DQ<3>
  VSS108  = GND
  \dqs5_b_c||tdqs5_b_c\  = M_B_CPU1_SB_DQS_DN<5>
  \dqs5_b_t||tdqs5_b_t\  = M_B_CPU1_SB_DQS_DP<5>
  VSS109  = GND
  DQ6_B  = M_B_CPU1_SB_DQ<6>
  VSS110  = GND
  DQ7_B  = M_B_CPU1_SB_DQ<7>
  VSS111  = GND
  DQ10_B  = M_B_CPU1_SB_DQ<10>
  VSS112  = GND
  DQ11_B  = M_B_CPU1_SB_DQ<11>
  VSS113  = GND
  \dqs6_b_c||tdqs6_b_c\  = M_B_CPU1_SB_DQS_DN<6>
  \dqs6_b_t||tdqs6_b_t\  = M_B_CPU1_SB_DQS_DP<6>
  VSS114  = GND
  DQ14_B  = M_B_CPU1_SB_DQ<14>
  VSS115  = GND
  DQ15_B  = M_B_CPU1_SB_DQ<15>
  VSS116  = GND
  DQ18_B  = M_B_CPU1_SB_DQ<18>
  VSS117  = GND
  DQ19_B  = M_B_CPU1_SB_DQ<19>
  VSS118  = GND
  \dqs7_b_c||tdqs7_b_c\  = M_B_CPU1_SB_DQS_DN<7>
  \dqs7_b_t||tdqs7_b_t\  = M_B_CPU1_SB_DQS_DP<7>
  VSS119  = GND
  DQ22_B  = M_B_CPU1_SB_DQ<22>
  VSS120  = GND
  DQ23_B  = M_B_CPU1_SB_DQ<23>
  VSS121  = GND
  DQ26_B  = M_B_CPU1_SB_DQ<26>
  VSS122  = GND
  DQ27_B  = M_B_CPU1_SB_DQ<27>
  VSS123  = GND
  \dqs8_b_c||tdqs8_b_c\  = M_B_CPU1_SB_DQS_DN<8>
  \dqs8_b_t||tdqs8_b_t\  = M_B_CPU1_SB_DQS_DP<8>
  VSS124  = GND
  DQ30_B  = M_B_CPU1_SB_DQ<30>
  VSS125  = GND
  DQ31_B  = M_B_CPU1_SB_DQ<31>
  VSS126  = GND
  G1  = GND
  G2  = GND
  G3  = GND

(kicad_pcb
	(version 20260206)
	(generator "pcbnew")
	(generator_version "10.0")
	(general
		(thickness 1.6)
		(legacy_teardrops no)
	)
	(paper "A4")
	(title_block
		(title "04192023_DAF0TMB3IC0_F0TG_MB_C_brd_V02_OCP.brd")
		(comment 1 "Grand Teton / footprint 4371 of 8354 (J26), pads 277-291 of 291")
	)
	(layers
		(0 "F.Cu" signal "TOP")
		(4 "In1.Cu" signal "GND")
		(6 "In2.Cu" signal "IN1")
		(8 "In3.Cu" signal "GND1")
		(10 "In4.Cu" signal "IN2")
		(12 "In5.Cu" signal "GND2")
		(14 "In6.Cu" signal "IN3")
		(16 "In7.Cu" signal "GND3")
		(18 "In8.Cu" signal "VCC")
		(20 "In9.Cu" signal "VCC1")
		(22 "In10.Cu" signal "GND4")
		(24 "In11.Cu" signal "IN4")
		(26 "In12.Cu" signal "GND5")
		(28 "In13.Cu" signal "IN5")
		(30 "In14.Cu" signal "GND6")
		(32 "In15.Cu" signal "IN6")
		(34 "In16.Cu" signal "GND7")
		(2 "B.Cu" signal "BOTTOM")
		(9 "F.Adhes" user "F.Adhesive")
		(11 "B.Adhes" user "B.Adhesive")
		(13 "F.Paste" user "Package Geometry/Pastemask Top")
		(15 "B.Paste" user "Package Geometry/Pastemask Bottom")
		(5 "F.SilkS" user "Ref Des/Silkscreen Top")
		(7 "B.SilkS" user "Ref Des/Silkscreen Bottom")
		(1 "F.Mask" user "Board Geometry/Soldermask Top")
		(3 "B.Mask" user "Board Geometry/Soldermask Bottom")
		(17 "Dwgs.User" user "User.Drawings")
		(19 "Cmts.User" user "User.Comments")
		(21 "Eco1.User" user "User.Eco1")
		(23 "Eco2.User" user "User.Eco2")
		(25 "Edge.Cuts" user "Board Geometry/Outline")
		(27 "Margin" user)
		(31 "F.CrtYd" user "Package Geometry/Place Bound Top")
		(29 "B.CrtYd" user "Package Geometry/Place Bound Bottom")
		(35 "F.Fab" user "Ref Des/Assembly Top")
		(33 "B.Fab" user "Ref Des/Assembly Bottom")
	)
	(footprint ""
		(layer "F.Cu")
		(at 49.834038 -255.560322 180)
		(property "Reference" "J26"
			(at -0.703326 -82.357722 0)
			(unlocked yes)
			(layer "F.SilkS")
			(effects
				(font
					(size 0.7874 0.5842)
					(thickness 0.1524)
				)
			)
		)
		(property "Value" ""
			(at 0 0 180)
			(layer "F.Fab")
			(effects
				(font
					(size 1.27 1.27)
				)
			)
		)
		(duplicate_pad_numbers_are_jumpers no)
		(pad "277" smd rect
			(at 2.050034 53.975 90)
			(size 0.519938 1.4986)
			(layers "F.Cu" "F.Mask" "F.Paste")
			(net "GND")
		)
		(pad "278" smd rect
			(at 2.050034 54.824884 90)
			(size 0.519938 1.4986)
			(layers "F.Cu" "F.Mask" "F.Paste")
			(net "M_B_CPU1_SB_DQ<26>")
		)
		(pad "279" smd rect
			(at 2.050034 55.675022 90)
			(size 0.519938 1.4986)
			(layers "F.Cu" "F.Mask" "F.Paste")
			(net "GND")
		)
		(pad "280" smd rect
			(at 2.050034 56.524906 90)
			(size 0.519938 1.4986)
			(layers "F.Cu" "F.Mask" "F.Paste")
			(net "M_B_CPU1_SB_DQ<27>")
		)
		(pad "281" smd rect
			(at 2.050034 57.375044 90)
			(size 0.519938 1.4986)
			(layers "F.Cu" "F.Mask" "F.Paste")
			(net "GND")
		)
		(pad "282" smd rect
			(at 2.050034 58.224928 90)
			(size 0.519938 1.4986)
			(layers "F.Cu" "F.Mask" "F.Paste")
			(net "M_B_CPU1_SB_DQS_DN<8>")
		)
		(pad "283" smd rect
			(at 2.050034 59.075066 90)
			(size 0.519938 1.4986)
			(layers "F.Cu" "F.Mask" "F.Paste")
			(net "M_B_CPU1_SB_DQS_DP<8>")
		)
		(pad "284" smd rect
			(at 2.050034 59.92495 90)
			(size 0.519938 1.4986)
			(layers "F.Cu" "F.Mask" "F.Paste")
			(net "GND")
		)
		(pad "285" smd rect
			(at 2.050034 60.775088 90)
			(size 0.519938 1.4986)
			(layers "F.Cu" "F.Mask" "F.Paste")
			(net "M_B_CPU1_SB_DQ<30>")
		)
		(pad "286" smd rect
			(at 2.050034 61.624972 90)
			(size 0.519938 1.4986)
			(layers "F.Cu" "F.Mask" "F.Paste")
			(net "GND")
		)
		(pad "287" smd rect
			(at 2.050034 62.47511 90)
			(size 0.519938 1.4986)
			(layers "F.Cu" "F.Mask" "F.Paste")
			(net "M_B_CPU1_SB_DQ<31>")
		)
		(pad "288" smd rect
			(at 2.050034 63.324994 90)
			(size 0.519938 1.4986)
			(layers "F.Cu" "F.Mask" "F.Paste")
			(net "GND")
		)
		(pad "G1" thru_hole oval
			(at 0 -68.97497 90)
			(size 1.7272 3.4798)
			(drill oval 1.2192 2.4638)
			(layers "*.Cu" "*.Mask")
			(remove_unused_layers no)
			(net "GND")
			(clearance 0.127)
			(thermal_gap 0.127)
		)
		(pad "G2" thru_hole oval
			(at 0 3.875024 90)
			(size 1.7272 3.4798)
			(drill oval 1.2192 2.4638)
			(layers "*.Cu" "*.Mask")
			(remove_unused_layers no)
			(net "GND")
			(clearance 0.127)
			(thermal_gap 0.127)
		)
		(pad "G3" thru_hole oval
			(at 0 68.97497 90)
			(size 1.7272 3.4798)
			(drill oval 1.2192 2.4638)
			(layers "*.Cu" "*.Mask")
			(remove_unused_layers no)
			(net "GND")
			(clearance 0.127)
			(thermal_gap 0.127)
		)
	)
)
